# BASEBOARD_FAB2 (Tioga Pass) — schematic netlist excerpt (pin names and nets, part order shuffled) for the footprints in the layout excerpt that follows; sources: Cadence DE-HDL packaged netlist, KiCad conversion of Wiwynn_Tioga_Pass_MB.brd

C22W23  SC22U16V5MX-4-GP  20%  pkg SMD-BCG5  page 236 : \1\ = VR_FET_SW_P12V_STBY_PVDDQ_DEF ; \2\ = GND
R2U29  RES  0.0 5% CHIP  pkg 0402  page 107 : A = P3E_CPU0_PE1_SS_RXN<7> ; B = P3E_CPU0_PE1_SS_R_RXN<7>
R7P16  RES  90.9 1% CHIP  pkg 0402  page 55 : A = A_CPU1_GHJ_RCOMP0 ; B = GND

(kicad_pcb
	(version 20260206)
	(generator "pcbnew")
	(generator_version "10.0")
	(general
		(thickness 1.6)
		(legacy_teardrops no)
	)
	(paper "A4")
	(title_block
		(title "Wiwynn_Tioga_Pass_MB.brd")
		(comment 1 "Tioga Pass / footprints 2755-2757 of 4770")
	)
	(layers
		(0 "F.Cu" signal "TOP")
		(4 "In1.Cu" signal "L2GND")
		(6 "In2.Cu" signal "L3")
		(8 "In3.Cu" signal "L4GND")
		(10 "In4.Cu" signal "L5")
		(12 "In5.Cu" signal "L6GND")
		(14 "In6.Cu" signal "L7VCC")
		(16 "In7.Cu" signal "L8VCC")
		(18 "In8.Cu" signal "L9GND")
		(20 "In9.Cu" signal "L10")
		(22 "In10.Cu" signal "L11GND")
		(24 "In11.Cu" signal "L12")
		(26 "In12.Cu" signal "L13GND")
		(2 "B.Cu" signal "BOTTOM")
		(9 "F.Adhes" user "F.Adhesive")
		(11 "B.Adhes" user "B.Adhesive")
		(13 "F.Paste" user "Package Geometry/Pastemask Top")
		(15 "B.Paste" user "Package Geometry/Pastemask Bottom")
		(5 "F.SilkS" user "Ref Des/Silkscreen Top")
		(7 "B.SilkS" user "Ref Des/Silkscreen Bottom")
		(1 "F.Mask" user "Board Geometry/Soldermask Top")
		(3 "B.Mask" user "Board Geometry/Soldermask Bottom")
		(17 "Dwgs.User" user "User.Drawings")
		(19 "Cmts.User" user "User.Comments")
		(21 "Eco1.User" user "User.Eco1")
		(23 "Eco2.User" user "User.Eco2")
		(25 "Edge.Cuts" user "Board Geometry/Outline")
		(27 "Margin" user)
		(31 "F.CrtYd" user "Package Geometry/Place Bound Top")
		(29 "B.CrtYd" user "Package Geometry/Place Bound Bottom")
		(35 "F.Fab" user "Ref Des/Assembly Top")
		(33 "B.Fab" user "Ref Des/Assembly Bottom")
	)
	(footprint ""
		(layer "B.Cu")
		(at 370.000276 -156.15158 180)
		(property "Reference" "C22W23"
			(at 0 0 0)
			(layer "B.SilkS")
			(hide yes)
			(effects
				(font
					(size 1.27 1.27)
				)
				(justify mirror)
			)
		)
		(property "Value" "*"
			(at 0.0762 -6.2357 180)
			(unlocked yes)
			(layer "B.Fab")
			(hide yes)
			(effects
				(font
					(size 1.27 1.016)
					(thickness 0.1524)
				)
				(justify mirror)
			)
		)
		(property "Device Type" "SC22U16V5MX-4-GP_SMD-BCG5-SC22A"
			(at 0.0762 -8.2677 180)
			(unlocked yes)
			(layer "B.Fab")
			(hide yes)
			(effects
				(font
					(size 1.27 1.016)
					(thickness 0.1524)
				)
				(justify mirror)
			)
		)
		(duplicate_pad_numbers_are_jumpers no)
		(fp_line
			(start -0.635 0)
			(end 0.635 0)
			(stroke
				(width 0.508)
				(type default)
			)
			(layer "B.SilkS")
		)
		(fp_rect
			(start 0.9652 1.778)
			(end -0.9652 -1.778)
			(stroke
				(width 0)
				(type default)
			)
			(fill no)
			(layer "B.CrtYd")
		)
		(fp_poly
			(pts
				(xy 0.9652 -1.778) (xy -0.9652 -1.778) (xy -0.9652 1.778) (xy 0.9652 1.778)
			)
			(stroke
				(width 0)
				(type default)
			)
			(fill no)
			(layer "B.Fab")
		)
		(pad "1" smd rect
			(at 0 -0.9652)
			(size 1.397 1.143)
			(layers "B.Cu" "B.Mask" "B.Paste")
			(net "VR_FET_SW_P12V_STBY_PVDDQ_DEF")
		)
		(pad "2" smd rect
			(at 0 0.9652)
			(size 1.397 1.143)
			(layers "B.Cu" "B.Mask" "B.Paste")
			(net "GND")
		)
	)
	(footprint ""
		(layer "B.Cu")
		(at 354.301806 -60.368434)
		(property "Reference" "R2U29"
			(at 0 0 0)
			(layer "B.SilkS")
			(hide yes)
			(effects
				(font
					(size 1.27 1.27)
				)
				(justify mirror)
			)
		)
		(property "Value" ""
			(at 0 0 0)
			(layer "B.Fab")
			(effects
				(font
					(size 1.27 1.27)
				)
				(justify mirror)
			)
		)
		(duplicate_pad_numbers_are_jumpers no)
		(fp_poly
			(pts
				(xy 0.2794 -0.1016) (xy -0.2794 -0.1016) (xy -0.2794 0.9906) (xy 0.2794 0.9906)
			)
			(stroke
				(width 0)
				(type default)
			)
			(fill no)
			(layer "B.CrtYd")
		)
		(fp_line
			(start -0.2794 -0.1016)
			(end 0.2794 -0.1016)
			(stroke
				(width 0.1)
				(type default)
			)
			(layer "B.Fab")
		)
		(fp_line
			(start -0.2794 0.9906)
			(end -0.2794 -0.1016)
			(stroke
				(width 0.1)
				(type default)
			)
			(layer "B.Fab")
		)
		(fp_line
			(start 0.2794 -0.1016)
			(end 0.2794 0.9906)
			(stroke
				(width 0.1)
				(type default)
			)
			(layer "B.Fab")
		)
		(fp_line
			(start 0.2794 0.9906)
			(end -0.2794 0.9906)
			(stroke
				(width 0.1)
				(type default)
			)
			(layer "B.Fab")
		)
		(pad "1" smd rect
			(at 0 0 180)
			(size 0.508 0.508)
			(layers "B.Cu" "B.Mask" "B.Paste")
			(net "P3E_CPU0_PE1_SS_RXN<7>")
		)
		(pad "2" smd rect
			(at 0 0.889 180)
			(size 0.508 0.508)
			(layers "B.Cu" "B.Mask" "B.Paste")
			(net "P3E_CPU0_PE1_SS_R_RXN<7>")
		)
		(zone
			(layer "B.Cu")
			(hatch none 0.5)
			(connect_pads
				(clearance 0)
			)
			(min_thickness 0.25)
			(keepout
				(tracks allowed)
				(vias not_allowed)
				(pads allowed)
				(copperpour not_allowed)
				(footprints allowed)
			)
			(placement
				(enabled no)
				(sheetname "")
			)
			(fill
				(thermal_gap 0.5)
				(thermal_bridge_width 0.5)
				(island_removal_mode 0)
			)
			(polygon
				(pts
					(xy 354.555806 -60.114434) (xy 354.047806 -60.114434) (xy 354.047806 -59.733434) (xy 354.555806 -59.733434)
				)
			)
		)
		(zone
			(layer "B.Cu")
			(hatch none 0.5)
			(connect_pads
				(clearance 0)
			)
			(min_thickness 0.25)
			(keepout
				(tracks not_allowed)
				(vias allowed)
				(pads allowed)
				(copperpour not_allowed)
				(footprints allowed)
			)
			(placement
				(enabled no)
				(sheetname "")
			)
			(fill
				(thermal_gap 0.5)
				(thermal_bridge_width 0.5)
				(island_removal_mode 0)
			)
			(polygon
				(pts
					(xy 354.555806 -59.733434) (xy 354.047806 -59.733434) (xy 354.047806 -60.114434) (xy 354.555806 -60.114434)
				)
			)
		)
	)
	(footprint ""
		(layer "B.Cu")
		(at 117.1956 -73.406 -90)
		(property "Reference" "R7P16"
			(at 0 0 90)
			(layer "B.SilkS")
			(hide yes)
			(effects
				(font
					(size 1.27 1.27)
				)
				(justify mirror)
			)
		)
		(property "Value" ""
			(at 0 0 90)
			(layer "B.Fab")
			(effects
				(font
					(size 1.27 1.27)
				)
				(justify mirror)
			)
		)
		(duplicate_pad_numbers_are_jumpers no)
		(fp_poly
			(pts
				(xy 0.2794 -0.1016) (xy -0.2794 -0.1016) (xy -0.2794 0.9906) (xy 0.2794 0.9906)
			)
			(stroke
				(width 0)
				(type default)
			)
			(fill no)
			(layer "B.CrtYd")
		)
		(fp_line
			(start -0.2794 0.9906)
			(end -0.2794 -0.1016)
			(stroke
				(width 0.1)
				(type default)
			)
			(layer "B.Fab")
		)
		(fp_line
			(start 0.2794 0.9906)
			(end -0.2794 0.9906)
			(stroke
				(width 0.1)
				(type default)
			)
			(layer "B.Fab")
		)
		(fp_line
			(start -0.2794 -0.1016)
			(end 0.2794 -0.1016)
			(stroke
				(width 0.1)
				(type default)
			)
			(layer "B.Fab")
		)
		(fp_line
			(start 0.2794 -0.1016)
			(end 0.2794 0.9906)
			(stroke
				(width 0.1)
				(type default)
			)
			(layer "B.Fab")
		)
		(pad "1" smd rect
			(at 0 0 90)
			(size 0.508 0.508)
			(layers "B.Cu" "B.Mask" "B.Paste")
			(net "A_CPU1_GHJ_RCOMP0")
		)
		(pad "2" smd rect
			(at 0 0.889 90)
			(size 0.508 0.508)
			(layers "B.Cu" "B.Mask" "B.Paste")
			(net "GND")
		)
		(zone
			(layer "B.Cu")
			(hatch none 0.5)
			(connect_pads
				(clearance 0)
			)
			(min_thickness 0.25)
			(keepout
				(tracks not_allowed)
				(vias allowed)
				(pads allowed)
				(copperpour not_allowed)
				(footprints allowed)
			)
			(placement
				(enabled no)
				(sheetname "")
			)
			(fill
				(thermal_gap 0.5)
				(thermal_bridge_width 0.5)
				(island_removal_mode 0)
			)
			(polygon
				(pts
					(xy 116.5606 -73.152) (xy 116.5606 -73.66) (xy 116.9416 -73.66) (xy 116.9416 -73.152)
				)
			)
		)
		(zone
			(layer "B.Cu")
			(hatch none 0.5)
			(connect_pads
				(clearance 0)
			)
			(min_thickness 0.25)
			(keepout
				(tracks allowed)
				(vias not_allowed)
				(pads allowed)
				(copperpour not_allowed)
				(footprints allowed)
			)
			(placement
				(enabled no)
				(sheetname "")
			)
			(fill
				(thermal_gap 0.5)
				(thermal_bridge_width 0.5)
				(island_removal_mode 0)
			)
			(polygon
				(pts
					(xy 116.9416 -73.152) (xy 116.9416 -73.66) (xy 116.5606 -73.66) (xy 116.5606 -73.152)
				)
			)
		)
	)
)
